(kicad_pcb
	(version 20260206)
	(generator "pcbnew")
	(generator_version "10.0")
	(general
		(thickness 1.6)
		(legacy_teardrops no)
	)
	(paper "A4")
	(title_block
		(title "Wiwynn_Tioga_Pass_MB.brd")
		(comment 1 "Tioga Pass / footprint 2717 of 4770 (J9L1), pads 124-243 of 291")
	)
	(layers
		(0 "F.Cu" signal "TOP")
		(4 "In1.Cu" signal "L2GND")
		(6 "In2.Cu" signal "L3")
		(8 "In3.Cu" signal "L4GND")
		(10 "In4.Cu" signal "L5")
		(12 "In5.Cu" signal "L6GND")
		(14 "In6.Cu" signal "L7VCC")
		(16 "In7.Cu" signal "L8VCC")
		(18 "In8.Cu" signal "L9GND")
		(20 "In9.Cu" signal "L10")
		(22 "In10.Cu" signal "L11GND")
		(24 "In11.Cu" signal "L12")
		(26 "In12.Cu" signal "L13GND")
		(2 "B.Cu" signal "BOTTOM")
		(9 "F.Adhes" user "F.Adhesive")
		(11 "B.Adhes" user "B.Adhesive")
		(13 "F.Paste" user "Package Geometry/Pastemask Top")
		(15 "B.Paste" user "Package Geometry/Pastemask Bottom")
		(5 "F.SilkS" user "Ref Des/Silkscreen Top")
		(7 "B.SilkS" user "Ref Des/Silkscreen Bottom")
		(1 "F.Mask" user "Board Geometry/Soldermask Top")
		(3 "B.Mask" user "Board Geometry/Soldermask Bottom")
		(17 "Dwgs.User" user "User.Drawings")
		(19 "Cmts.User" user "User.Comments")
		(21 "Eco1.User" user "User.Eco1")
		(23 "Eco2.User" user "User.Eco2")
		(25 "Edge.Cuts" user "Board Geometry/Outline")
		(27 "Margin" user)
		(31 "F.CrtYd" user "Package Geometry/Place Bound Top")
		(29 "B.CrtYd" user "Package Geometry/Place Bound Bottom")
		(35 "F.Fab" user "Ref Des/Assembly Top")
		(33 "B.Fab" user "Ref Des/Assembly Bottom")
	)
	(footprint ""
		(layer "B.Cu")
		(at 29.699458 -152.078436 90)
		(property "Reference" "J9L1"
			(at 2.200148 37.737542 0)
			(unlocked yes)
			(layer "B.SilkS")
			(effects
				(font
					(size 0.7874 0.5842)
					(thickness 0.1524)
				)
				(justify left mirror)
			)
		)
		(property "Value" ""
			(at 0 0 90)
			(layer "B.Fab")
			(effects
				(font
					(size 1.27 1.27)
				)
				(justify mirror)
			)
		)
		(duplicate_pad_numbers_are_jumpers no)
		(pad "121" smd rect
			(at 0 107.100116 270)
			(size 1.8034 0.508)
			(layers "B.Cu" "B.Mask" "B.Paste")
			(net "M_M_DQS_DP<15>")
		)
		(pad "122" smd rect
			(at 0 107.95 270)
			(size 1.8034 0.508)
			(layers "B.Cu" "B.Mask" "B.Paste")
			(net "M_M_DQS_DN<15>")
		)
		(pad "123" smd rect
			(at 0 108.799884 270)
			(size 1.8034 0.508)
			(layers "B.Cu" "B.Mask" "B.Paste")
			(net "GND")
		)
		(pad "124" smd rect
			(at 0 109.650022 270)
			(size 1.8034 0.508)
			(layers "B.Cu" "B.Mask" "B.Paste")
			(net "M_M_DQ<54>")
		)
		(pad "125" smd rect
			(at 0 110.499906 270)
			(size 1.8034 0.508)
			(layers "B.Cu" "B.Mask" "B.Paste")
			(net "GND")
		)
		(pad "126" smd rect
			(at 0 111.350044 270)
			(size 1.8034 0.508)
			(layers "B.Cu" "B.Mask" "B.Paste")
			(net "M_M_DQ<50>")
		)
		(pad "127" smd rect
			(at 0 112.199928 270)
			(size 1.8034 0.508)
			(layers "B.Cu" "B.Mask" "B.Paste")
			(net "GND")
		)
		(pad "128" smd rect
			(at 0 113.050066 270)
			(size 1.8034 0.508)
			(layers "B.Cu" "B.Mask" "B.Paste")
			(net "M_M_DQ<60>")
		)
		(pad "129" smd rect
			(at 0 113.89995 270)
			(size 1.8034 0.508)
			(layers "B.Cu" "B.Mask" "B.Paste")
			(net "GND")
		)
		(pad "130" smd rect
			(at 0 114.750088 270)
			(size 1.8034 0.508)
			(layers "B.Cu" "B.Mask" "B.Paste")
			(net "M_M_DQ<56>")
		)
		(pad "131" smd rect
			(at 0 115.599972 270)
			(size 1.8034 0.508)
			(layers "B.Cu" "B.Mask" "B.Paste")
			(net "GND")
		)
		(pad "132" smd rect
			(at 0 116.45011 270)
			(size 1.8034 0.508)
			(layers "B.Cu" "B.Mask" "B.Paste")
			(net "M_M_DQS_DP<16>")
		)
		(pad "133" smd rect
			(at 0 117.299994 270)
			(size 1.8034 0.508)
			(layers "B.Cu" "B.Mask" "B.Paste")
			(net "M_M_DQS_DN<16>")
		)
		(pad "134" smd rect
			(at 0 118.149878 270)
			(size 1.8034 0.508)
			(layers "B.Cu" "B.Mask" "B.Paste")
			(net "GND")
		)
		(pad "135" smd rect
			(at 0 119.000016 270)
			(size 1.8034 0.508)
			(layers "B.Cu" "B.Mask" "B.Paste")
			(net "M_M_DQ<62>")
		)
		(pad "136" smd rect
			(at 0 119.8499 270)
			(size 1.8034 0.508)
			(layers "B.Cu" "B.Mask" "B.Paste")
			(net "GND")
		)
		(pad "137" smd rect
			(at 0 120.700038 270)
			(size 1.8034 0.508)
			(layers "B.Cu" "B.Mask" "B.Paste")
			(net "M_M_DQ<58>")
		)
		(pad "138" smd rect
			(at 0 121.549922 270)
			(size 1.8034 0.508)
			(layers "B.Cu" "B.Mask" "B.Paste")
			(net "GND")
		)
		(pad "139" smd rect
			(at 0 122.40006 270)
			(size 1.8034 0.508)
			(layers "B.Cu" "B.Mask" "B.Paste")
			(net "PVPP_KLM")
		)
		(pad "140" smd rect
			(at 0 123.249944 270)
			(size 1.8034 0.508)
			(layers "B.Cu" "B.Mask" "B.Paste")
			(net "GND")
		)
		(pad "141" smd rect
			(at 0 124.100082 270)
			(size 1.8034 0.508)
			(layers "B.Cu" "B.Mask" "B.Paste")
			(net "SMB_DDR_KLM_VPP_SCL")
		)
		(pad "142" smd rect
			(at 0 124.949966 270)
			(size 1.8034 0.508)
			(layers "B.Cu" "B.Mask" "B.Paste")
			(net "PVPP_KLM")
		)
		(pad "143" smd rect
			(at 0 125.800104 270)
			(size 1.8034 0.508)
			(layers "B.Cu" "B.Mask" "B.Paste")
			(net "PVPP_KLM")
		)
		(pad "144" smd rect
			(at 0 126.649988 270)
			(size 1.8034 0.508)
			(layers "B.Cu" "B.Mask" "B.Paste")
			(net "TP_CH_M_DIMM_M1_RFU_2")
		)
		(pad "145" smd rect
			(at -4.59994 0 270)
			(size 1.8034 0.508)
			(layers "B.Cu" "B.Mask" "B.Paste")
			(net "P12V_NVDIMM_KLM")
		)
		(pad "146" smd rect
			(at -4.59994 0.849884 270)
			(size 1.8034 0.508)
			(layers "B.Cu" "B.Mask" "B.Paste")
			(net "M_M_VREF")
		)
		(pad "147" smd rect
			(at -4.59994 1.700022 270)
			(size 1.8034 0.508)
			(layers "B.Cu" "B.Mask" "B.Paste")
			(net "GND")
		)
		(pad "148" smd rect
			(at -4.59994 2.549906 270)
			(size 1.8034 0.508)
			(layers "B.Cu" "B.Mask" "B.Paste")
			(net "M_M_DQ<5>")
		)
		(pad "149" smd rect
			(at -4.59994 3.400044 270)
			(size 1.8034 0.508)
			(layers "B.Cu" "B.Mask" "B.Paste")
			(net "GND")
		)
		(pad "150" smd rect
			(at -4.59994 4.249928 270)
			(size 1.8034 0.508)
			(layers "B.Cu" "B.Mask" "B.Paste")
			(net "M_M_DQ<1>")
		)
		(pad "151" smd rect
			(at -4.59994 5.100066 270)
			(size 1.8034 0.508)
			(layers "B.Cu" "B.Mask" "B.Paste")
			(net "GND")
		)
		(pad "152" smd rect
			(at -4.59994 5.94995 270)
			(size 1.8034 0.508)
			(layers "B.Cu" "B.Mask" "B.Paste")
			(net "M_M_DQS_DN<0>")
		)
		(pad "153" smd rect
			(at -4.59994 6.800088 270)
			(size 1.8034 0.508)
			(layers "B.Cu" "B.Mask" "B.Paste")
			(net "M_M_DQS_DP<0>")
		)
		(pad "154" smd rect
			(at -4.59994 7.649972 270)
			(size 1.8034 0.508)
			(layers "B.Cu" "B.Mask" "B.Paste")
			(net "GND")
		)
		(pad "155" smd rect
			(at -4.59994 8.50011 270)
			(size 1.8034 0.508)
			(layers "B.Cu" "B.Mask" "B.Paste")
			(net "M_M_DQ<7>")
		)
		(pad "156" smd rect
			(at -4.59994 9.349994 270)
			(size 1.8034 0.508)
			(layers "B.Cu" "B.Mask" "B.Paste")
			(net "GND")
		)
		(pad "157" smd rect
			(at -4.59994 10.199878 270)
			(size 1.8034 0.508)
			(layers "B.Cu" "B.Mask" "B.Paste")
			(net "M_M_DQ<3>")
		)
		(pad "158" smd rect
			(at -4.59994 11.050016 270)
			(size 1.8034 0.508)
			(layers "B.Cu" "B.Mask" "B.Paste")
			(net "GND")
		)
		(pad "159" smd rect
			(at -4.59994 11.8999 270)
			(size 1.8034 0.508)
			(layers "B.Cu" "B.Mask" "B.Paste")
			(net "M_M_DQ<13>")
		)
		(pad "160" smd rect
			(at -4.59994 12.750038 270)
			(size 1.8034 0.508)
			(layers "B.Cu" "B.Mask" "B.Paste")
			(net "GND")
		)
		(pad "161" smd rect
			(at -4.59994 13.599922 270)
			(size 1.8034 0.508)
			(layers "B.Cu" "B.Mask" "B.Paste")
			(net "M_M_DQ<9>")
		)
		(pad "162" smd rect
			(at -4.59994 14.45006 270)
			(size 1.8034 0.508)
			(layers "B.Cu" "B.Mask" "B.Paste")
			(net "GND")
		)
		(pad "163" smd rect
			(at -4.59994 15.299944 270)
			(size 1.8034 0.508)
			(layers "B.Cu" "B.Mask" "B.Paste")
			(net "M_M_DQS_DN<1>")
		)
		(pad "164" smd rect
			(at -4.59994 16.150082 270)
			(size 1.8034 0.508)
			(layers "B.Cu" "B.Mask" "B.Paste")
			(net "M_M_DQS_DP<1>")
		)
		(pad "165" smd rect
			(at -4.59994 16.999966 270)
			(size 1.8034 0.508)
			(layers "B.Cu" "B.Mask" "B.Paste")
			(net "GND")
		)
		(pad "166" smd rect
			(at -4.59994 17.850104 270)
			(size 1.8034 0.508)
			(layers "B.Cu" "B.Mask" "B.Paste")
			(net "M_M_DQ<15>")
		)
		(pad "167" smd rect
			(at -4.59994 18.699988 270)
			(size 1.8034 0.508)
			(layers "B.Cu" "B.Mask" "B.Paste")
			(net "GND")
		)
		(pad "168" smd rect
			(at -4.59994 19.550126 270)
			(size 1.8034 0.508)
			(layers "B.Cu" "B.Mask" "B.Paste")
			(net "M_M_DQ<11>")
		)
		(pad "169" smd rect
			(at -4.59994 20.40001 270)
			(size 1.8034 0.508)
			(layers "B.Cu" "B.Mask" "B.Paste")
			(net "GND")
		)
		(pad "170" smd rect
			(at -4.59994 21.249894 270)
			(size 1.8034 0.508)
			(layers "B.Cu" "B.Mask" "B.Paste")
			(net "M_M_DQ<21>")
		)
		(pad "171" smd rect
			(at -4.59994 22.100032 270)
			(size 1.8034 0.508)
			(layers "B.Cu" "B.Mask" "B.Paste")
			(net "GND")
		)
		(pad "172" smd rect
			(at -4.59994 22.949916 270)
			(size 1.8034 0.508)
			(layers "B.Cu" "B.Mask" "B.Paste")
			(net "M_M_DQ<17>")
		)
		(pad "173" smd rect
			(at -4.59994 23.800054 270)
			(size 1.8034 0.508)
			(layers "B.Cu" "B.Mask" "B.Paste")
			(net "GND")
		)
		(pad "174" smd rect
			(at -4.59994 24.649938 270)
			(size 1.8034 0.508)
			(layers "B.Cu" "B.Mask" "B.Paste")
			(net "M_M_DQS_DN<2>")
		)
		(pad "175" smd rect
			(at -4.59994 25.500076 270)
			(size 1.8034 0.508)
			(layers "B.Cu" "B.Mask" "B.Paste")
			(net "M_M_DQS_DP<2>")
		)
		(pad "176" smd rect
			(at -4.59994 26.34996 270)
			(size 1.8034 0.508)
			(layers "B.Cu" "B.Mask" "B.Paste")
			(net "GND")
		)
		(pad "177" smd rect
			(at -4.59994 27.200098 270)
			(size 1.8034 0.508)
			(layers "B.Cu" "B.Mask" "B.Paste")
			(net "M_M_DQ<23>")
		)
		(pad "178" smd rect
			(at -4.59994 28.049982 270)
			(size 1.8034 0.508)
			(layers "B.Cu" "B.Mask" "B.Paste")
			(net "GND")
		)
		(pad "179" smd rect
			(at -4.59994 28.90012 270)
			(size 1.8034 0.508)
			(layers "B.Cu" "B.Mask" "B.Paste")
			(net "M_M_DQ<19>")
		)
		(pad "180" smd rect
			(at -4.59994 29.750004 270)
			(size 1.8034 0.508)
			(layers "B.Cu" "B.Mask" "B.Paste")
			(net "GND")
		)
		(pad "181" smd rect
			(at -4.59994 30.599888 270)
			(size 1.8034 0.508)
			(layers "B.Cu" "B.Mask" "B.Paste")
			(net "M_M_DQ<29>")
		)
		(pad "182" smd rect
			(at -4.59994 31.450026 270)
			(size 1.8034 0.508)
			(layers "B.Cu" "B.Mask" "B.Paste")
			(net "GND")
		)
		(pad "183" smd rect
			(at -4.59994 32.29991 270)
			(size 1.8034 0.508)
			(layers "B.Cu" "B.Mask" "B.Paste")
			(net "M_M_DQ<25>")
		)
		(pad "184" smd rect
			(at -4.59994 33.150048 270)
			(size 1.8034 0.508)
			(layers "B.Cu" "B.Mask" "B.Paste")
			(net "GND")
		)
		(pad "185" smd rect
			(at -4.59994 33.999932 270)
			(size 1.8034 0.508)
			(layers "B.Cu" "B.Mask" "B.Paste")
			(net "M_M_DQS_DN<3>")
		)
		(pad "186" smd rect
			(at -4.59994 34.85007 270)
			(size 1.8034 0.508)
			(layers "B.Cu" "B.Mask" "B.Paste")
			(net "M_M_DQS_DP<3>")
		)
		(pad "187" smd rect
			(at -4.59994 35.699954 270)
			(size 1.8034 0.508)
			(layers "B.Cu" "B.Mask" "B.Paste")
			(net "GND")
		)
		(pad "188" smd rect
			(at -4.59994 36.550092 270)
			(size 1.8034 0.508)
			(layers "B.Cu" "B.Mask" "B.Paste")
			(net "M_M_DQ<31>")
		)
		(pad "189" smd rect
			(at -4.59994 37.399976 270)
			(size 1.8034 0.508)
			(layers "B.Cu" "B.Mask" "B.Paste")
			(net "GND")
		)
		(pad "190" smd rect
			(at -4.59994 38.250114 270)
			(size 1.8034 0.508)
			(layers "B.Cu" "B.Mask" "B.Paste")
			(net "M_M_DQ<27>")
		)
		(pad "191" smd rect
			(at -4.59994 39.099998 270)
			(size 1.8034 0.508)
			(layers "B.Cu" "B.Mask" "B.Paste")
			(net "GND")
		)
		(pad "192" smd rect
			(at -4.59994 39.949882 270)
			(size 1.8034 0.508)
			(layers "B.Cu" "B.Mask" "B.Paste")
			(net "M_M_ECC<5>")
		)
		(pad "193" smd rect
			(at -4.59994 40.80002 270)
			(size 1.8034 0.508)
			(layers "B.Cu" "B.Mask" "B.Paste")
			(net "GND")
		)
		(pad "194" smd rect
			(at -4.59994 41.649904 270)
			(size 1.8034 0.508)
			(layers "B.Cu" "B.Mask" "B.Paste")
			(net "M_M_ECC<1>")
		)
		(pad "195" smd rect
			(at -4.59994 42.500042 270)
			(size 1.8034 0.508)
			(layers "B.Cu" "B.Mask" "B.Paste")
			(net "GND")
		)
		(pad "196" smd rect
			(at -4.59994 43.349926 270)
			(size 1.8034 0.508)
			(layers "B.Cu" "B.Mask" "B.Paste")
			(net "M_M_DQS_DN<8>")
		)
		(pad "197" smd rect
			(at -4.59994 44.200064 270)
			(size 1.8034 0.508)
			(layers "B.Cu" "B.Mask" "B.Paste")
			(net "M_M_DQS_DP<8>")
		)
		(pad "198" smd rect
			(at -4.59994 45.049948 270)
			(size 1.8034 0.508)
			(layers "B.Cu" "B.Mask" "B.Paste")
			(net "GND")
		)
		(pad "199" smd rect
			(at -4.59994 45.900086 270)
			(size 1.8034 0.508)
			(layers "B.Cu" "B.Mask" "B.Paste")
			(net "M_M_ECC<7>")
		)
		(pad "200" smd rect
			(at -4.59994 46.74997 270)
			(size 1.8034 0.508)
			(layers "B.Cu" "B.Mask" "B.Paste")
			(net "GND")
		)
		(pad "201" smd rect
			(at -4.59994 47.600108 270)
			(size 1.8034 0.508)
			(layers "B.Cu" "B.Mask" "B.Paste")
			(net "M_M_ECC<3>")
		)
		(pad "202" smd rect
			(at -4.59994 48.449992 270)
			(size 1.8034 0.508)
			(layers "B.Cu" "B.Mask" "B.Paste")
			(net "GND")
		)
		(pad "203" smd rect
			(at -4.59994 49.299876 270)
			(size 1.8034 0.508)
			(layers "B.Cu" "B.Mask" "B.Paste")
			(net "M_M_CKE<3>")
		)
		(pad "204" smd rect
			(at -4.59994 50.150014 270)
			(size 1.8034 0.508)
			(layers "B.Cu" "B.Mask" "B.Paste")
			(net "PVDDQ_KLM")
		)
		(pad "205" smd rect
			(at -4.59994 50.999898 270)
			(size 1.8034 0.508)
			(layers "B.Cu" "B.Mask" "B.Paste")
			(net "TP_CH_M_DIMM_M1_RFU_0")
		)
		(pad "206" smd rect
			(at -4.59994 51.850036 270)
			(size 1.8034 0.508)
			(layers "B.Cu" "B.Mask" "B.Paste")
			(net "PVDDQ_KLM")
		)
		(pad "207" smd rect
			(at -4.59994 52.69992 270)
			(size 1.8034 0.508)
			(layers "B.Cu" "B.Mask" "B.Paste")
			(net "M_M_BG<1>")
		)
		(pad "208" smd rect
			(at -4.59994 53.550058 270)
			(size 1.8034 0.508)
			(layers "B.Cu" "B.Mask" "B.Paste")
			(net "M_M_ALERT_N")
		)
		(pad "209" smd rect
			(at -4.59994 54.399942 270)
			(size 1.8034 0.508)
			(layers "B.Cu" "B.Mask" "B.Paste")
			(net "PVDDQ_KLM")
		)
		(pad "210" smd rect
			(at -4.59994 55.25008 270)
			(size 1.8034 0.508)
			(layers "B.Cu" "B.Mask" "B.Paste")
			(net "M_M_MA<11>")
		)
		(pad "211" smd rect
			(at -4.59994 56.099964 270)
			(size 1.8034 0.508)
			(layers "B.Cu" "B.Mask" "B.Paste")
			(net "M_M_MA<7>")
		)
		(pad "212" smd rect
			(at -4.59994 56.950102 270)
			(size 1.8034 0.508)
			(layers "B.Cu" "B.Mask" "B.Paste")
			(net "PVDDQ_KLM")
		)
		(pad "213" smd rect
			(at -4.59994 57.799986 270)
			(size 1.8034 0.508)
			(layers "B.Cu" "B.Mask" "B.Paste")
			(net "M_M_MA<5>")
		)
		(pad "214" smd rect
			(at -4.59994 58.650124 270)
			(size 1.8034 0.508)
			(layers "B.Cu" "B.Mask" "B.Paste")
			(net "M_M_MA<4>")
		)
		(pad "215" smd rect
			(at -4.59994 59.500008 270)
			(size 1.8034 0.508)
			(layers "B.Cu" "B.Mask" "B.Paste")
			(net "PVDDQ_KLM")
		)
		(pad "216" smd rect
			(at -4.59994 60.349892 270)
			(size 1.8034 0.508)
			(layers "B.Cu" "B.Mask" "B.Paste")
			(net "M_M_MA<2>")
		)
		(pad "217" smd rect
			(at -4.59994 61.20003 270)
			(size 1.8034 0.508)
			(layers "B.Cu" "B.Mask" "B.Paste")
			(net "PVDDQ_KLM")
		)
		(pad "218" smd rect
			(at -4.59994 62.049914 270)
			(size 1.8034 0.508)
			(layers "B.Cu" "B.Mask" "B.Paste")
			(net "M_M_CLK_DP<3>")
		)
		(pad "219" smd rect
			(at -4.59994 62.900052 270)
			(size 1.8034 0.508)
			(layers "B.Cu" "B.Mask" "B.Paste")
			(net "M_M_CLK_DN<3>")
		)
		(pad "220" smd rect
			(at -4.59994 63.749936 270)
			(size 1.8034 0.508)
			(layers "B.Cu" "B.Mask" "B.Paste")
			(net "PVDDQ_KLM")
		)
		(pad "221" smd rect
			(at -4.59994 64.600074 270)
			(size 1.8034 0.508)
			(layers "B.Cu" "B.Mask" "B.Paste")
			(net "PVTT_KLM")
		)
		(pad "222" smd rect
			(at -4.59994 70.550024 270)
			(size 1.8034 0.508)
			(layers "B.Cu" "B.Mask" "B.Paste")
			(net "M_M_PAR")
		)
		(pad "223" smd rect
			(at -4.59994 71.399908 270)
			(size 1.8034 0.508)
			(layers "B.Cu" "B.Mask" "B.Paste")
			(net "PVDDQ_KLM")
		)
		(pad "224" smd rect
			(at -4.59994 72.250046 270)
			(size 1.8034 0.508)
			(layers "B.Cu" "B.Mask" "B.Paste")
			(net "M_M_BA<1>")
		)
		(pad "225" smd rect
			(at -4.59994 73.09993 270)
			(size 1.8034 0.508)
			(layers "B.Cu" "B.Mask" "B.Paste")
			(net "M_M_MA<10>")
		)
		(pad "226" smd rect
			(at -4.59994 73.950068 270)
			(size 1.8034 0.508)
			(layers "B.Cu" "B.Mask" "B.Paste")
			(net "PVDDQ_KLM")
		)
		(pad "227" smd rect
			(at -4.59994 74.799952 270)
			(size 1.8034 0.508)
			(layers "B.Cu" "B.Mask" "B.Paste")
			(net "TP_CH_M_DIMM_M1_RFU_1")
		)
		(pad "228" smd rect
			(at -4.59994 75.65009 270)
			(size 1.8034 0.508)
			(layers "B.Cu" "B.Mask" "B.Paste")
			(net "M_M_MA<14>")
		)
		(pad "229" smd rect
			(at -4.59994 76.499974 270)
			(size 1.8034 0.508)
			(layers "B.Cu" "B.Mask" "B.Paste")
			(net "PVDDQ_KLM")
		)
		(pad "230" smd rect
			(at -4.59994 77.350112 270)
			(size 1.8034 0.508)
			(layers "B.Cu" "B.Mask" "B.Paste")
			(net "FM_ADR_COMPLETE_KLM_N")
		)
		(pad "231" smd rect
			(at -4.59994 78.199996 270)
			(size 1.8034 0.508)
			(layers "B.Cu" "B.Mask" "B.Paste")
			(net "PVDDQ_KLM")
		)
		(pad "232" smd rect
			(at -4.59994 79.04988 270)
			(size 1.8034 0.508)
			(layers "B.Cu" "B.Mask" "B.Paste")
			(net "M_M_MA<13>")
		)
		(pad "233" smd rect
			(at -4.59994 79.900018 270)
			(size 1.8034 0.508)
			(layers "B.Cu" "B.Mask" "B.Paste")
			(net "PVDDQ_KLM")
		)
		(pad "234" smd rect
			(at -4.59994 80.749902 270)
			(size 1.8034 0.508)
			(layers "B.Cu" "B.Mask" "B.Paste")
			(net "M_M_MA<17>")
		)
		(pad "235" smd rect
			(at -4.59994 81.60004 270)
			(size 1.8034 0.508)
			(layers "B.Cu" "B.Mask" "B.Paste")
			(net "M_M_C<2>")
		)
		(pad "236" smd rect
			(at -4.59994 82.449924 270)
			(size 1.8034 0.508)
			(layers "B.Cu" "B.Mask" "B.Paste")
			(net "PVDDQ_KLM")
		)
		(pad "237" smd rect
			(at -4.59994 83.300062 270)
			(size 1.8034 0.508)
			(layers "B.Cu" "B.Mask" "B.Paste")
			(net "M_M_CS_N<7>")
		)
		(pad "238" smd rect
			(at -4.59994 84.149946 270)
			(size 1.8034 0.508)
			(layers "B.Cu" "B.Mask" "B.Paste")
			(net "PVPP_KLM")
		)
		(pad "239" smd rect
			(at -4.59994 85.000084 270)
			(size 1.8034 0.508)
			(layers "B.Cu" "B.Mask" "B.Paste")
			(net "GND")
		)
		(pad "240" smd rect
			(at -4.59994 85.849968 270)
			(size 1.8034 0.508)
			(layers "B.Cu" "B.Mask" "B.Paste")
			(net "M_M_DQ<37>")
		)
	)
)
